# S9S_MB_2U (Grand Teton) — schematic netlist excerpt (pin names and nets, part order shuffled) for the footprints in the layout excerpt that follows; sources: Cadence DE-HDL packaged netlist, KiCad conversion of 03242023_DA0F0TMBIJ0_F0T_Motherboard_J_brd_V01_OCP.brd

PD101  DIODE_TVS  SMF14A IC  pkg SOD123F  page 156 : A = GND ; C = P12V_AUX
C608  Q_CAP  0.1UF 25V 10% X7R  pkg 0402  page 202 : A = PGPPA_AUX ; B = GND

(kicad_pcb
	(version 20260206)
	(generator "pcbnew")
	(generator_version "10.0")
	(general
		(thickness 1.6)
		(legacy_teardrops no)
	)
	(paper "A4")
	(title_block
		(title "03242023_DA0F0TMBIJ0_F0T_Motherboard_J_brd_V01_OCP.brd")
		(comment 1 "Grand Teton / footprints 4033-4034 of 6105")
	)
	(layers
		(0 "F.Cu" signal "TOP")
		(4 "In1.Cu" signal "GND")
		(6 "In2.Cu" signal "IN1")
		(8 "In3.Cu" signal "GND1")
		(10 "In4.Cu" signal "IN2")
		(12 "In5.Cu" signal "GND2")
		(14 "In6.Cu" signal "IN3")
		(16 "In7.Cu" signal "GND3")
		(18 "In8.Cu" signal "VCC")
		(20 "In9.Cu" signal "VCC1")
		(22 "In10.Cu" signal "GND4")
		(24 "In11.Cu" signal "IN4")
		(26 "In12.Cu" signal "GND5")
		(28 "In13.Cu" signal "IN5")
		(30 "In14.Cu" signal "GND6")
		(32 "In15.Cu" signal "IN6")
		(34 "In16.Cu" signal "GND7")
		(2 "B.Cu" signal "BOTTOM")
		(9 "F.Adhes" user "F.Adhesive")
		(11 "B.Adhes" user "B.Adhesive")
		(13 "F.Paste" user "Package Geometry/Pastemask Top")
		(15 "B.Paste" user "Package Geometry/Pastemask Bottom")
		(5 "F.SilkS" user "Ref Des/Silkscreen Top")
		(7 "B.SilkS" user "Ref Des/Silkscreen Bottom")
		(1 "F.Mask" user "Board Geometry/Soldermask Top")
		(3 "B.Mask" user "Board Geometry/Soldermask Bottom")
		(17 "Dwgs.User" user "User.Drawings")
		(19 "Cmts.User" user "User.Comments")
		(21 "Eco1.User" user "User.Eco1")
		(23 "Eco2.User" user "User.Eco2")
		(25 "Edge.Cuts" user "Board Geometry/Outline")
		(27 "Margin" user)
		(31 "F.CrtYd" user "Package Geometry/Place Bound Top")
		(29 "B.CrtYd" user "Package Geometry/Place Bound Bottom")
		(35 "F.Fab" user "Ref Des/Assembly Top")
		(33 "B.Fab" user "Ref Des/Assembly Bottom")
	)
	(footprint ""
		(layer "F.Cu")
		(at 451.327012 -30.397958 -90)
		(property "Reference" "PD101"
			(at -0.14224 -1.991868 0)
			(unlocked yes)
			(layer "F.SilkS")
			(effects
				(font
					(size 0.7874 0.5842)
					(thickness 0.1524)
				)
				(justify left)
			)
		)
		(property "Value" ""
			(at 0 0 270)
			(layer "F.Fab")
			(effects
				(font
					(size 1.27 1.27)
				)
			)
		)
		(duplicate_pad_numbers_are_jumpers no)
		(fp_line
			(start -2.250186 0.999998)
			(end 2.631186 0.999998)
			(stroke
				(width 0.1524)
				(type default)
			)
			(layer "F.SilkS")
		)
		(fp_line
			(start 2.631186 0.999998)
			(end 2.631186 -0.999998)
			(stroke
				(width 0.1524)
				(type default)
			)
			(layer "F.SilkS")
		)
		(fp_line
			(start -0.381 0.3302)
			(end -0.381 -0.4318)
			(stroke
				(width 0.1524)
				(type default)
			)
			(layer "F.SilkS")
		)
		(fp_line
			(start -0.381 -0.0508)
			(end -0.6604 -0.0508)
			(stroke
				(width 0.1524)
				(type default)
			)
			(layer "F.SilkS")
		)
		(fp_line
			(start 0.381 -0.0508)
			(end -0.381 0.3302)
			(stroke
				(width 0.1524)
				(type default)
			)
			(layer "F.SilkS")
		)
		(fp_line
			(start 0.381 -0.0508)
			(end 0.635 -0.0508)
			(stroke
				(width 0.1524)
				(type default)
			)
			(layer "F.SilkS")
		)
		(fp_line
			(start -0.381 -0.4318)
			(end 0.381 -0.0508)
			(stroke
				(width 0.1524)
				(type default)
			)
			(layer "F.SilkS")
		)
		(fp_line
			(start 0.381 -0.4318)
			(end 0.381 0.3302)
			(stroke
				(width 0.1524)
				(type default)
			)
			(layer "F.SilkS")
		)
		(fp_line
			(start -2.250186 -0.999998)
			(end -2.250186 0.999998)
			(stroke
				(width 0.1524)
				(type default)
			)
			(layer "F.SilkS")
		)
		(fp_line
			(start 2.631186 -0.999998)
			(end -2.250186 -0.999998)
			(stroke
				(width 0.1524)
				(type default)
			)
			(layer "F.SilkS")
		)
		(fp_rect
			(start 2.6162 1.016)
			(end 2.1844 -0.9652)
			(stroke
				(width 0)
				(type default)
			)
			(fill yes)
			(layer "F.SilkS")
		)
		(fp_line
			(start -1.450086 0.999998)
			(end 1.450086 0.999998)
			(stroke
				(width 0.1)
				(type default)
			)
			(layer "F.Fab")
		)
		(fp_line
			(start 1.450086 0.999998)
			(end 1.450086 -0.999998)
			(stroke
				(width 0.1)
				(type default)
			)
			(layer "F.Fab")
		)
		(fp_line
			(start -1.450086 -0.999998)
			(end -1.450086 0.999998)
			(stroke
				(width 0.1)
				(type default)
			)
			(layer "F.Fab")
		)
		(fp_line
			(start 1.450086 -0.999998)
			(end -1.450086 -0.999998)
			(stroke
				(width 0.1)
				(type default)
			)
			(layer "F.Fab")
		)
		(fp_text user "+"
			(at -4.56057 -0.126238 270)
			(unlocked yes)
			(layer "F.SilkS")
			(effects
				(font
					(size 1.905 1.4224)
					(thickness 0.1524)
				)
				(justify left)
			)
		)
		(fp_text user "-"
			(at 2.4384 -0.22225 270)
			(unlocked yes)
			(layer "F.SilkS")
			(effects
				(font
					(size 1.905 1.4224)
					(thickness 0.1524)
				)
				(justify left)
			)
		)
		(fp_text user "+"
			(at -3.4798 -0.22225 270)
			(unlocked yes)
			(layer "F.Fab")
			(effects
				(font
					(size 1.905 1.4224)
					(thickness 0.1524)
				)
				(justify left)
			)
		)
		(fp_text user "-"
			(at 2.4384 -0.22225 270)
			(unlocked yes)
			(layer "F.Fab")
			(effects
				(font
					(size 1.905 1.4224)
					(thickness 0.1524)
				)
				(justify left)
			)
		)
		(pad "A" smd rect
			(at -1.450086 0 270)
			(size 1.3208 1.4224)
			(layers "F.Cu" "F.Mask" "F.Paste")
			(net "GND")
		)
		(pad "C" smd rect
			(at 1.450086 0 270)
			(size 1.3208 1.4224)
			(layers "F.Cu" "F.Mask" "F.Paste")
			(net "P12V_AUX")
		)
	)
	(footprint ""
		(layer "F.Cu")
		(at 334.174846 -18.79727 -90)
		(property "Reference" "C608"
			(at 0 0 270)
			(layer "F.SilkS")
			(hide yes)
			(effects
				(font
					(size 1.27 1.27)
				)
			)
		)
		(property "Value" ""
			(at 0 0 270)
			(layer "F.Fab")
			(effects
				(font
					(size 1.27 1.27)
				)
			)
		)
		(duplicate_pad_numbers_are_jumpers no)
		(fp_line
			(start -0.7874 0.4064)
			(end -0.7874 -0.4064)
			(stroke
				(width 0.1524)
				(type default)
			)
			(layer "F.SilkS")
		)
		(fp_line
			(start 0.7874 0.4064)
			(end -0.7874 0.4064)
			(stroke
				(width 0.1524)
				(type default)
			)
			(layer "F.SilkS")
		)
		(fp_line
			(start -0.7874 -0.4064)
			(end 0.7874 -0.4064)
			(stroke
				(width 0.1524)
				(type default)
			)
			(layer "F.SilkS")
		)
		(fp_line
			(start 0.7874 -0.4064)
			(end 0.7874 0.4064)
			(stroke
				(width 0.1524)
				(type default)
			)
			(layer "F.SilkS")
		)
		(fp_line
			(start -0.67945 0.3048)
			(end -0.67945 -0.305054)
			(stroke
				(width 0.1)
				(type default)
			)
			(layer "F.Fab")
		)
		(fp_line
			(start -0.12065 0.3048)
			(end -0.67945 0.3048)
			(stroke
				(width 0.1)
				(type default)
			)
			(layer "F.Fab")
		)
		(fp_line
			(start 0.120396 0.3048)
			(end 0.120396 0.2794)
			(stroke
				(width 0.1)
				(type default)
			)
			(layer "F.Fab")
		)
		(fp_line
			(start 0.67945 0.3048)
			(end 0.120396 0.3048)
			(stroke
				(width 0.1)
				(type default)
			)
			(layer "F.Fab")
		)
		(fp_line
			(start -0.12065 0.2794)
			(end -0.12065 0.3048)
			(stroke
				(width 0.1)
				(type default)
			)
			(layer "F.Fab")
		)
		(fp_line
			(start 0.120396 0.2794)
			(end -0.12065 0.2794)
			(stroke
				(width 0.1)
				(type default)
			)
			(layer "F.Fab")
		)
		(fp_line
			(start -0.12065 -0.2794)
			(end 0.12065 -0.2794)
			(stroke
				(width 0.1)
				(type default)
			)
			(layer "F.Fab")
		)
		(fp_line
			(start 0.12065 -0.2794)
			(end 0.12065 -0.3048)
			(stroke
				(width 0.1)
				(type default)
			)
			(layer "F.Fab")
		)
		(fp_line
			(start 0.12065 -0.3048)
			(end 0.67945 -0.3048)
			(stroke
				(width 0.1)
				(type default)
			)
			(layer "F.Fab")
		)
		(fp_line
			(start 0.67945 -0.3048)
			(end 0.67945 0.3048)
			(stroke
				(width 0.1)
				(type default)
			)
			(layer "F.Fab")
		)
		(fp_line
			(start -0.67945 -0.305054)
			(end -0.12065 -0.305054)
			(stroke
				(width 0.1)
				(type default)
			)
			(layer "F.Fab")
		)
		(fp_line
			(start -0.12065 -0.305054)
			(end -0.12065 -0.2794)
			(stroke
				(width 0.1)
				(type default)
			)
			(layer "F.Fab")
		)
		(pad "1" smd circle
			(at -0.40005 0 270)
			(size 0 0)
			(layers "F.Cu" "F.Mask" "F.Paste")
			(net "PGPPA_AUX")
		)
		(pad "2" smd circle
			(at 0.40005 0 270)
			(size 0 0)
			(layers "F.Cu" "F.Mask" "F.Paste")
			(net "GND")
		)
	)
)
